# S9S_MB_2U (Grand Teton) — schematic netlist excerpt (pin names and nets, part order shuffled) for the footprints in the layout excerpt that follows; sources: Cadence DE-HDL packaged netlist, KiCad conversion of 03242023_DA0F0TMBIJ0_F0T_Motherboard_J_brd_V01_OCP.brd

PC246_P0_8  Q_CAP  22UF 4V 20% X6S  pkg C0805  page 270 : A = PVCCIN_CPU0 ; B = GND
R600  Q_RES  0 5% CHIP  pkg 0402LF  page 241 : A = I3C_SPD_DDREFGH_CPU1_BMC_R_SDA ; B = I3C_SPD_DDREFGH_CPU1_BMC_SDA
C81  Q_CAP  2.2UF 6.3V 20% X6S  pkg C0402  page 110 : A = P3V3_AUX ; B = GND

(kicad_pcb
	(version 20260206)
	(generator "pcbnew")
	(generator_version "10.0")
	(general
		(thickness 1.6)
		(legacy_teardrops no)
	)
	(paper "A4")
	(title_block
		(title "03242023_DA0F0TMBIJ0_F0T_Motherboard_J_brd_V01_OCP.brd")
		(comment 1 "Grand Teton / footprints 5764-5766 of 6105")
	)
	(layers
		(0 "F.Cu" signal "TOP")
		(4 "In1.Cu" signal "GND")
		(6 "In2.Cu" signal "IN1")
		(8 "In3.Cu" signal "GND1")
		(10 "In4.Cu" signal "IN2")
		(12 "In5.Cu" signal "GND2")
		(14 "In6.Cu" signal "IN3")
		(16 "In7.Cu" signal "GND3")
		(18 "In8.Cu" signal "VCC")
		(20 "In9.Cu" signal "VCC1")
		(22 "In10.Cu" signal "GND4")
		(24 "In11.Cu" signal "IN4")
		(26 "In12.Cu" signal "GND5")
		(28 "In13.Cu" signal "IN5")
		(30 "In14.Cu" signal "GND6")
		(32 "In15.Cu" signal "IN6")
		(34 "In16.Cu" signal "GND7")
		(2 "B.Cu" signal "BOTTOM")
		(9 "F.Adhes" user "F.Adhesive")
		(11 "B.Adhes" user "B.Adhesive")
		(13 "F.Paste" user "Package Geometry/Pastemask Top")
		(15 "B.Paste" user "Package Geometry/Pastemask Bottom")
		(5 "F.SilkS" user "Ref Des/Silkscreen Top")
		(7 "B.SilkS" user "Ref Des/Silkscreen Bottom")
		(1 "F.Mask" user "Board Geometry/Soldermask Top")
		(3 "B.Mask" user "Board Geometry/Soldermask Bottom")
		(17 "Dwgs.User" user "User.Drawings")
		(19 "Cmts.User" user "User.Comments")
		(21 "Eco1.User" user "User.Eco1")
		(23 "Eco2.User" user "User.Eco2")
		(25 "Edge.Cuts" user "Board Geometry/Outline")
		(27 "Margin" user)
		(31 "F.CrtYd" user "Package Geometry/Place Bound Top")
		(29 "B.CrtYd" user "Package Geometry/Place Bound Bottom")
		(35 "F.Fab" user "Ref Des/Assembly Top")
		(33 "B.Fab" user "Ref Des/Assembly Bottom")
	)
	(footprint ""
		(layer "B.Cu")
		(at 182.867046 -13.60043 -90)
		(property "Reference" "R600"
			(at 0 0 90)
			(layer "B.SilkS")
			(hide yes)
			(effects
				(font
					(size 1.27 1.27)
				)
				(justify mirror)
			)
		)
		(property "Value" ""
			(at 0 0 90)
			(layer "B.Fab")
			(effects
				(font
					(size 1.27 1.27)
				)
				(justify mirror)
			)
		)
		(duplicate_pad_numbers_are_jumpers no)
		(fp_line
			(start -0.7874 0.4064)
			(end 0.7874 0.4064)
			(stroke
				(width 0.1524)
				(type default)
			)
			(layer "B.SilkS")
		)
		(fp_line
			(start 0.7874 0.4064)
			(end 0.7874 -0.4064)
			(stroke
				(width 0.1524)
				(type default)
			)
			(layer "B.SilkS")
		)
		(fp_line
			(start -0.7874 -0.4064)
			(end -0.7874 0.4064)
			(stroke
				(width 0.1524)
				(type default)
			)
			(layer "B.SilkS")
		)
		(fp_line
			(start 0.7874 -0.4064)
			(end -0.7874 -0.4064)
			(stroke
				(width 0.1524)
				(type default)
			)
			(layer "B.SilkS")
		)
		(fp_line
			(start -0.67945 0.3048)
			(end -0.120396 0.3048)
			(stroke
				(width 0.1)
				(type default)
			)
			(layer "B.Fab")
		)
		(fp_line
			(start -0.120396 0.3048)
			(end -0.120396 0.2794)
			(stroke
				(width 0.1)
				(type default)
			)
			(layer "B.Fab")
		)
		(fp_line
			(start 0.12065 0.3048)
			(end 0.67945 0.3048)
			(stroke
				(width 0.1)
				(type default)
			)
			(layer "B.Fab")
		)
		(fp_line
			(start 0.67945 0.3048)
			(end 0.67945 -0.305054)
			(stroke
				(width 0.1)
				(type default)
			)
			(layer "B.Fab")
		)
		(fp_line
			(start -0.120396 0.2794)
			(end 0.12065 0.2794)
			(stroke
				(width 0.1)
				(type default)
			)
			(layer "B.Fab")
		)
		(fp_line
			(start 0.12065 0.2794)
			(end 0.12065 0.3048)
			(stroke
				(width 0.1)
				(type default)
			)
			(layer "B.Fab")
		)
		(fp_line
			(start -0.12065 -0.2794)
			(end -0.12065 -0.3048)
			(stroke
				(width 0.1)
				(type default)
			)
			(layer "B.Fab")
		)
		(fp_line
			(start 0.12065 -0.2794)
			(end -0.12065 -0.2794)
			(stroke
				(width 0.1)
				(type default)
			)
			(layer "B.Fab")
		)
		(fp_line
			(start -0.67945 -0.3048)
			(end -0.67945 0.3048)
			(stroke
				(width 0.1)
				(type default)
			)
			(layer "B.Fab")
		)
		(fp_line
			(start -0.12065 -0.3048)
			(end -0.67945 -0.3048)
			(stroke
				(width 0.1)
				(type default)
			)
			(layer "B.Fab")
		)
		(fp_line
			(start 0.12065 -0.305054)
			(end 0.12065 -0.2794)
			(stroke
				(width 0.1)
				(type default)
			)
			(layer "B.Fab")
		)
		(fp_line
			(start 0.67945 -0.305054)
			(end 0.12065 -0.305054)
			(stroke
				(width 0.1)
				(type default)
			)
			(layer "B.Fab")
		)
		(pad "1" smd circle
			(at 0.40005 0 90)
			(size 0 0)
			(layers "B.Cu" "B.Mask" "B.Paste")
			(net "I3C_SPD_DDREFGH_CPU1_BMC_R_SDA")
		)
		(pad "2" smd circle
			(at -0.40005 0 90)
			(size 0 0)
			(layers "B.Cu" "B.Mask" "B.Paste")
			(net "I3C_SPD_DDREFGH_CPU1_BMC_SDA")
		)
	)
	(footprint ""
		(layer "B.Cu")
		(at 384.484372 -331.58938 -90)
		(property "Reference" "PC246_P0_8"
			(at 0 0 90)
			(layer "B.SilkS")
			(hide yes)
			(effects
				(font
					(size 1.27 1.27)
				)
				(justify mirror)
			)
		)
		(property "Value" ""
			(at 0 0 90)
			(layer "B.Fab")
			(effects
				(font
					(size 1.27 1.27)
				)
				(justify mirror)
			)
		)
		(duplicate_pad_numbers_are_jumpers no)
		(fp_line
			(start -1.524 0.762)
			(end 1.524 0.762)
			(stroke
				(width 0.1524)
				(type default)
			)
			(layer "B.SilkS")
		)
		(fp_line
			(start 1.524 0.762)
			(end 1.524 -0.762)
			(stroke
				(width 0.1524)
				(type default)
			)
			(layer "B.SilkS")
		)
		(fp_line
			(start -1.524 -0.762)
			(end -1.524 0.762)
			(stroke
				(width 0.1524)
				(type default)
			)
			(layer "B.SilkS")
		)
		(fp_line
			(start 1.524 -0.762)
			(end -1.524 -0.762)
			(stroke
				(width 0.1524)
				(type default)
			)
			(layer "B.SilkS")
		)
		(fp_line
			(start -1.1049 0.724916)
			(end -1.1049 -0.724916)
			(stroke
				(width 0.1)
				(type default)
			)
			(layer "B.Fab")
		)
		(fp_line
			(start 1.1049 0.724916)
			(end -1.1049 0.724916)
			(stroke
				(width 0.1)
				(type default)
			)
			(layer "B.Fab")
		)
		(fp_line
			(start -1.1049 -0.724916)
			(end 1.1049 -0.724916)
			(stroke
				(width 0.1)
				(type default)
			)
			(layer "B.Fab")
		)
		(fp_line
			(start 1.1049 -0.724916)
			(end 1.1049 0.724916)
			(stroke
				(width 0.1)
				(type default)
			)
			(layer "B.Fab")
		)
		(pad "1" smd rect
			(at 0.889 0 270)
			(size 1.016 1.27)
			(layers "B.Cu" "B.Mask" "B.Paste")
			(net "PVCCIN_CPU0")
		)
		(pad "2" smd rect
			(at -0.889 0 270)
			(size 1.016 1.27)
			(layers "B.Cu" "B.Mask" "B.Paste")
			(net "GND")
		)
	)
	(footprint ""
		(layer "B.Cu")
		(at 196.544946 -319.268856 180)
		(property "Reference" "C81"
			(at 0 0 0)
			(layer "B.SilkS")
			(hide yes)
			(effects
				(font
					(size 1.27 1.27)
				)
				(justify mirror)
			)
		)
		(property "Value" ""
			(at 0 0 0)
			(layer "B.Fab")
			(effects
				(font
					(size 1.27 1.27)
				)
				(justify mirror)
			)
		)
		(duplicate_pad_numbers_are_jumpers no)
		(fp_line
			(start 0.7874 0.4064)
			(end 0.7874 -0.4064)
			(stroke
				(width 0.1524)
				(type default)
			)
			(layer "B.SilkS")
		)
		(fp_line
			(start 0.7874 -0.4064)
			(end -0.7874 -0.4064)
			(stroke
				(width 0.1524)
				(type default)
			)
			(layer "B.SilkS")
		)
		(fp_line
			(start -0.7874 0.4064)
			(end 0.7874 0.4064)
			(stroke
				(width 0.1524)
				(type default)
			)
			(layer "B.SilkS")
		)
		(fp_line
			(start -0.7874 -0.4064)
			(end -0.7874 0.4064)
			(stroke
				(width 0.1524)
				(type default)
			)
			(layer "B.SilkS")
		)
		(fp_line
			(start 0.67945 0.3048)
			(end 0.67945 -0.305054)
			(stroke
				(width 0.1)
				(type default)
			)
			(layer "B.Fab")
		)
		(fp_line
			(start 0.67945 -0.305054)
			(end 0.12065 -0.305054)
			(stroke
				(width 0.1)
				(type default)
			)
			(layer "B.Fab")
		)
		(fp_line
			(start 0.12065 0.3048)
			(end 0.67945 0.3048)
			(stroke
				(width 0.1)
				(type default)
			)
			(layer "B.Fab")
		)
		(fp_line
			(start 0.12065 0.2794)
			(end 0.12065 0.3048)
			(stroke
				(width 0.1)
				(type default)
			)
			(layer "B.Fab")
		)
		(fp_line
			(start 0.12065 -0.2794)
			(end -0.12065 -0.2794)
			(stroke
				(width 0.1)
				(type default)
			)
			(layer "B.Fab")
		)
		(fp_line
			(start 0.12065 -0.305054)
			(end 0.12065 -0.2794)
			(stroke
				(width 0.1)
				(type default)
			)
			(layer "B.Fab")
		)
		(fp_line
			(start -0.120396 0.3048)
			(end -0.120396 0.2794)
			(stroke
				(width 0.1)
				(type default)
			)
			(layer "B.Fab")
		)
		(fp_line
			(start -0.120396 0.2794)
			(end 0.12065 0.2794)
			(stroke
				(width 0.1)
				(type default)
			)
			(layer "B.Fab")
		)
		(fp_line
			(start -0.12065 -0.2794)
			(end -0.12065 -0.3048)
			(stroke
				(width 0.1)
				(type default)
			)
			(layer "B.Fab")
		)
		(fp_line
			(start -0.12065 -0.3048)
			(end -0.67945 -0.3048)
			(stroke
				(width 0.1)
				(type default)
			)
			(layer "B.Fab")
		)
		(fp_line
			(start -0.67945 0.3048)
			(end -0.120396 0.3048)
			(stroke
				(width 0.1)
				(type default)
			)
			(layer "B.Fab")
		)
		(fp_line
			(start -0.67945 -0.3048)
			(end -0.67945 0.3048)
			(stroke
				(width 0.1)
				(type default)
			)
			(layer "B.Fab")
		)
		(pad "1" smd circle
			(at 0.40005 0)
			(size 0 0)
			(layers "B.Cu" "B.Mask" "B.Paste")
			(net "P3V3_AUX")
		)
		(pad "2" smd circle
			(at -0.40005 0)
			(size 0 0)
			(layers "B.Cu" "B.Mask" "B.Paste")
			(net "GND")
		)
	)
)
